# S9S_MB_2U (Grand Teton) — schematic netlist excerpt (pin names and nets, part order shuffled) for the footprints in the layout excerpt that follows; sources: Cadence DE-HDL packaged netlist, KiCad conversion of 03242023_DA0F0TMBIJ0_F0T_Motherboard_J_brd_V01_OCP.brd

R1955  Q_RES  10K 1% CHIP  pkg 0402LF  page 204 : A = P3V3_AUX ; B = FM_PCHHOT_N
PC2187  Q_CAP  1UF 25V 10% X6S  pkg C0402  page 301 : A = HSC_VDD_R ; B = AGND_HSC

(kicad_pcb
	(version 20260206)
	(generator "pcbnew")
	(generator_version "10.0")
	(general
		(thickness 1.6)
		(legacy_teardrops no)
	)
	(paper "A4")
	(title_block
		(title "03242023_DA0F0TMBIJ0_F0T_Motherboard_J_brd_V01_OCP.brd")
		(comment 1 "Grand Teton / footprints 2388-2389 of 6105")
	)
	(layers
		(0 "F.Cu" signal "TOP")
		(4 "In1.Cu" signal "GND")
		(6 "In2.Cu" signal "IN1")
		(8 "In3.Cu" signal "GND1")
		(10 "In4.Cu" signal "IN2")
		(12 "In5.Cu" signal "GND2")
		(14 "In6.Cu" signal "IN3")
		(16 "In7.Cu" signal "GND3")
		(18 "In8.Cu" signal "VCC")
		(20 "In9.Cu" signal "VCC1")
		(22 "In10.Cu" signal "GND4")
		(24 "In11.Cu" signal "IN4")
		(26 "In12.Cu" signal "GND5")
		(28 "In13.Cu" signal "IN5")
		(30 "In14.Cu" signal "GND6")
		(32 "In15.Cu" signal "IN6")
		(34 "In16.Cu" signal "GND7")
		(2 "B.Cu" signal "BOTTOM")
		(9 "F.Adhes" user "F.Adhesive")
		(11 "B.Adhes" user "B.Adhesive")
		(13 "F.Paste" user "Package Geometry/Pastemask Top")
		(15 "B.Paste" user "Package Geometry/Pastemask Bottom")
		(5 "F.SilkS" user "Ref Des/Silkscreen Top")
		(7 "B.SilkS" user "Ref Des/Silkscreen Bottom")
		(1 "F.Mask" user "Board Geometry/Soldermask Top")
		(3 "B.Mask" user "Board Geometry/Soldermask Bottom")
		(17 "Dwgs.User" user "User.Drawings")
		(19 "Cmts.User" user "User.Comments")
		(21 "Eco1.User" user "User.Eco1")
		(23 "Eco2.User" user "User.Eco2")
		(25 "Edge.Cuts" user "Board Geometry/Outline")
		(27 "Margin" user)
		(31 "F.CrtYd" user "Package Geometry/Place Bound Top")
		(29 "B.CrtYd" user "Package Geometry/Place Bound Bottom")
		(35 "F.Fab" user "Ref Des/Assembly Top")
		(33 "B.Fab" user "Ref Des/Assembly Bottom")
	)
	(footprint ""
		(layer "F.Cu")
		(at 309.519066 -43.92803 180)
		(property "Reference" "R1955"
			(at 0 0 180)
			(layer "F.SilkS")
			(hide yes)
			(effects
				(font
					(size 1.27 1.27)
				)
			)
		)
		(property "Value" ""
			(at 0 0 180)
			(layer "F.Fab")
			(effects
				(font
					(size 1.27 1.27)
				)
			)
		)
		(duplicate_pad_numbers_are_jumpers no)
		(fp_line
			(start 0.7874 0.4064)
			(end -0.7874 0.4064)
			(stroke
				(width 0.1524)
				(type default)
			)
			(layer "F.SilkS")
		)
		(fp_line
			(start 0.7874 -0.4064)
			(end 0.7874 0.4064)
			(stroke
				(width 0.1524)
				(type default)
			)
			(layer "F.SilkS")
		)
		(fp_line
			(start -0.7874 0.4064)
			(end -0.7874 -0.4064)
			(stroke
				(width 0.1524)
				(type default)
			)
			(layer "F.SilkS")
		)
		(fp_line
			(start -0.7874 -0.4064)
			(end 0.7874 -0.4064)
			(stroke
				(width 0.1524)
				(type default)
			)
			(layer "F.SilkS")
		)
		(fp_line
			(start 0.67945 0.3048)
			(end 0.120396 0.3048)
			(stroke
				(width 0.1)
				(type default)
			)
			(layer "F.Fab")
		)
		(fp_line
			(start 0.67945 -0.3048)
			(end 0.67945 0.3048)
			(stroke
				(width 0.1)
				(type default)
			)
			(layer "F.Fab")
		)
		(fp_line
			(start 0.12065 -0.2794)
			(end 0.12065 -0.3048)
			(stroke
				(width 0.1)
				(type default)
			)
			(layer "F.Fab")
		)
		(fp_line
			(start 0.12065 -0.3048)
			(end 0.67945 -0.3048)
			(stroke
				(width 0.1)
				(type default)
			)
			(layer "F.Fab")
		)
		(fp_line
			(start 0.120396 0.3048)
			(end 0.120396 0.2794)
			(stroke
				(width 0.1)
				(type default)
			)
			(layer "F.Fab")
		)
		(fp_line
			(start 0.120396 0.2794)
			(end -0.12065 0.2794)
			(stroke
				(width 0.1)
				(type default)
			)
			(layer "F.Fab")
		)
		(fp_line
			(start -0.12065 0.3048)
			(end -0.67945 0.3048)
			(stroke
				(width 0.1)
				(type default)
			)
			(layer "F.Fab")
		)
		(fp_line
			(start -0.12065 0.2794)
			(end -0.12065 0.3048)
			(stroke
				(width 0.1)
				(type default)
			)
			(layer "F.Fab")
		)
		(fp_line
			(start -0.12065 -0.2794)
			(end 0.12065 -0.2794)
			(stroke
				(width 0.1)
				(type default)
			)
			(layer "F.Fab")
		)
		(fp_line
			(start -0.12065 -0.305054)
			(end -0.12065 -0.2794)
			(stroke
				(width 0.1)
				(type default)
			)
			(layer "F.Fab")
		)
		(fp_line
			(start -0.67945 0.3048)
			(end -0.67945 -0.305054)
			(stroke
				(width 0.1)
				(type default)
			)
			(layer "F.Fab")
		)
		(fp_line
			(start -0.67945 -0.305054)
			(end -0.12065 -0.305054)
			(stroke
				(width 0.1)
				(type default)
			)
			(layer "F.Fab")
		)
		(pad "1" smd circle
			(at -0.40005 0 180)
			(size 0 0)
			(layers "F.Cu" "F.Mask" "F.Paste")
			(net "P3V3_AUX")
		)
		(pad "2" smd circle
			(at 0.40005 0 180)
			(size 0 0)
			(layers "F.Cu" "F.Mask" "F.Paste")
			(net "FM_PCHHOT_N")
		)
	)
	(footprint ""
		(layer "F.Cu")
		(at 179.352448 -403.271482 180)
		(property "Reference" "PC2187"
			(at 0 0 180)
			(layer "F.SilkS")
			(hide yes)
			(effects
				(font
					(size 1.27 1.27)
				)
			)
		)
		(property "Value" ""
			(at 0 0 180)
			(layer "F.Fab")
			(effects
				(font
					(size 1.27 1.27)
				)
			)
		)
		(duplicate_pad_numbers_are_jumpers no)
		(fp_line
			(start 0.7874 0.4064)
			(end -0.7874 0.4064)
			(stroke
				(width 0.1524)
				(type default)
			)
			(layer "F.SilkS")
		)
		(fp_line
			(start 0.7874 -0.4064)
			(end 0.7874 0.4064)
			(stroke
				(width 0.1524)
				(type default)
			)
			(layer "F.SilkS")
		)
		(fp_line
			(start -0.7874 0.4064)
			(end -0.7874 -0.4064)
			(stroke
				(width 0.1524)
				(type default)
			)
			(layer "F.SilkS")
		)
		(fp_line
			(start -0.7874 -0.4064)
			(end 0.7874 -0.4064)
			(stroke
				(width 0.1524)
				(type default)
			)
			(layer "F.SilkS")
		)
		(fp_line
			(start 0.67945 0.3048)
			(end 0.120396 0.3048)
			(stroke
				(width 0.1)
				(type default)
			)
			(layer "F.Fab")
		)
		(fp_line
			(start 0.67945 -0.3048)
			(end 0.67945 0.3048)
			(stroke
				(width 0.1)
				(type default)
			)
			(layer "F.Fab")
		)
		(fp_line
			(start 0.12065 -0.2794)
			(end 0.12065 -0.3048)
			(stroke
				(width 0.1)
				(type default)
			)
			(layer "F.Fab")
		)
		(fp_line
			(start 0.12065 -0.3048)
			(end 0.67945 -0.3048)
			(stroke
				(width 0.1)
				(type default)
			)
			(layer "F.Fab")
		)
		(fp_line
			(start 0.120396 0.3048)
			(end 0.120396 0.2794)
			(stroke
				(width 0.1)
				(type default)
			)
			(layer "F.Fab")
		)
		(fp_line
			(start 0.120396 0.2794)
			(end -0.12065 0.2794)
			(stroke
				(width 0.1)
				(type default)
			)
			(layer "F.Fab")
		)
		(fp_line
			(start -0.12065 0.3048)
			(end -0.67945 0.3048)
			(stroke
				(width 0.1)
				(type default)
			)
			(layer "F.Fab")
		)
		(fp_line
			(start -0.12065 0.2794)
			(end -0.12065 0.3048)
			(stroke
				(width 0.1)
				(type default)
			)
			(layer "F.Fab")
		)
		(fp_line
			(start -0.12065 -0.2794)
			(end 0.12065 -0.2794)
			(stroke
				(width 0.1)
				(type default)
			)
			(layer "F.Fab")
		)
		(fp_line
			(start -0.12065 -0.305054)
			(end -0.12065 -0.2794)
			(stroke
				(width 0.1)
				(type default)
			)
			(layer "F.Fab")
		)
		(fp_line
			(start -0.67945 0.3048)
			(end -0.67945 -0.305054)
			(stroke
				(width 0.1)
				(type default)
			)
			(layer "F.Fab")
		)
		(fp_line
			(start -0.67945 -0.305054)
			(end -0.12065 -0.305054)
			(stroke
				(width 0.1)
				(type default)
			)
			(layer "F.Fab")
		)
		(pad "1" smd circle
			(at -0.40005 0 180)
			(size 0 0)
			(layers "F.Cu" "F.Mask" "F.Paste")
			(net "HSC_VDD_R")
		)
		(pad "2" smd circle
			(at 0.40005 0 180)
			(size 0 0)
			(layers "F.Cu" "F.Mask" "F.Paste")
			(net "AGND_HSC")
		)
	)
)
